(kicad_pcb
	(version 20260206)
	(generator "pcbnew")
	(generator_version "10.0")
	(general
		(thickness 1.6)
		(legacy_teardrops no)
	)
	(paper "A4")
	(title_block
		(title "Wiwynn_Tioga_Pass_MB.brd")
		(comment 1 "Tioga Pass / footprints 2961-2967 of 4770")
	)
	(layers
		(0 "F.Cu" signal "TOP")
		(4 "In1.Cu" signal "L2GND")
		(6 "In2.Cu" signal "L3")
		(8 "In3.Cu" signal "L4GND")
		(10 "In4.Cu" signal "L5")
		(12 "In5.Cu" signal "L6GND")
		(14 "In6.Cu" signal "L7VCC")
		(16 "In7.Cu" signal "L8VCC")
		(18 "In8.Cu" signal "L9GND")
		(20 "In9.Cu" signal "L10")
		(22 "In10.Cu" signal "L11GND")
		(24 "In11.Cu" signal "L12")
		(26 "In12.Cu" signal "L13GND")
		(2 "B.Cu" signal "BOTTOM")
		(9 "F.Adhes" user "F.Adhesive")
		(11 "B.Adhes" user "B.Adhesive")
		(13 "F.Paste" user "Package Geometry/Pastemask Top")
		(15 "B.Paste" user "Package Geometry/Pastemask Bottom")
		(5 "F.SilkS" user "Ref Des/Silkscreen Top")
		(7 "B.SilkS" user "Ref Des/Silkscreen Bottom")
		(1 "F.Mask" user "Board Geometry/Soldermask Top")
		(3 "B.Mask" user "Board Geometry/Soldermask Bottom")
		(17 "Dwgs.User" user "User.Drawings")
		(19 "Cmts.User" user "User.Comments")
		(21 "Eco1.User" user "User.Eco1")
		(23 "Eco2.User" user "User.Eco2")
		(25 "Edge.Cuts" user "Board Geometry/Outline")
		(27 "Margin" user)
		(31 "F.CrtYd" user "Package Geometry/Place Bound Top")
		(29 "B.CrtYd" user "Package Geometry/Place Bound Bottom")
		(35 "F.Fab" user "Ref Des/Assembly Top")
		(33 "B.Fab" user "Ref Des/Assembly Bottom")
	)
	(footprint ""
		(layer "B.Cu")
		(at 445.4906 -64.7446 180)
		(property "Reference" "C2P13"
			(at 0 0 0)
			(layer "B.SilkS")
			(hide yes)
			(effects
				(font
					(size 1.27 1.27)
				)
				(justify mirror)
			)
		)
		(property "Value" ""
			(at 0 0 0)
			(layer "B.Fab")
			(effects
				(font
					(size 1.27 1.27)
				)
				(justify mirror)
			)
		)
		(duplicate_pad_numbers_are_jumpers no)
		(fp_poly
			(pts
				(xy -0.3048 -0.1016) (xy -0.3048 0.9906) (xy 0.3048 0.9906) (xy 0.3048 -0.1016)
			)
			(stroke
				(width 0)
				(type default)
			)
			(fill no)
			(layer "B.CrtYd")
		)
		(fp_line
			(start 0.3048 0.9906)
			(end -0.3048 0.9906)
			(stroke
				(width 0.1)
				(type default)
			)
			(layer "B.Fab")
		)
		(fp_line
			(start 0.3048 -0.1016)
			(end 0.3048 0.9906)
			(stroke
				(width 0.1)
				(type default)
			)
			(layer "B.Fab")
		)
		(fp_line
			(start -0.3048 0.9906)
			(end -0.3048 -0.1016)
			(stroke
				(width 0.1)
				(type default)
			)
			(layer "B.Fab")
		)
		(fp_line
			(start -0.3048 -0.1016)
			(end 0.3048 -0.1016)
			(stroke
				(width 0.1)
				(type default)
			)
			(layer "B.Fab")
		)
		(pad "1" smd rect
			(at 0 0)
			(size 0.508 0.508)
			(layers "B.Cu" "B.Mask" "B.Paste")
			(net "P12V_STBY")
		)
		(pad "2" smd rect
			(at 0 0.889)
			(size 0.508 0.508)
			(layers "B.Cu" "B.Mask" "B.Paste")
			(net "GND")
		)
		(zone
			(layer "B.Cu")
			(hatch none 0.5)
			(connect_pads
				(clearance 0)
			)
			(min_thickness 0.25)
			(keepout
				(tracks not_allowed)
				(vias allowed)
				(pads allowed)
				(copperpour not_allowed)
				(footprints allowed)
			)
			(placement
				(enabled no)
				(sheetname "")
			)
			(fill
				(thermal_gap 0.5)
				(thermal_bridge_width 0.5)
				(island_removal_mode 0)
			)
			(polygon
				(pts
					(xy 445.2366 -65.3796) (xy 445.7446 -65.3796) (xy 445.7446 -64.9986) (xy 445.2366 -64.9986)
				)
			)
		)
		(zone
			(layer "B.Cu")
			(hatch none 0.5)
			(connect_pads
				(clearance 0)
			)
			(min_thickness 0.25)
			(keepout
				(tracks allowed)
				(vias not_allowed)
				(pads allowed)
				(copperpour not_allowed)
				(footprints allowed)
			)
			(placement
				(enabled no)
				(sheetname "")
			)
			(fill
				(thermal_gap 0.5)
				(thermal_bridge_width 0.5)
				(island_removal_mode 0)
			)
			(polygon
				(pts
					(xy 445.2366 -64.9986) (xy 445.7446 -64.9986) (xy 445.7446 -65.3796) (xy 445.2366 -65.3796)
				)
			)
		)
	)
	(footprint ""
		(layer "B.Cu")
		(at 370.290852 -46.788578)
		(property "Reference" "U2T4"
			(at -5.093716 -1.536192 180)
			(unlocked yes)
			(layer "B.SilkS")
			(effects
				(font
					(size 0.7874 0.5842)
					(thickness 0.1524)
				)
				(justify left mirror)
			)
		)
		(property "Value" ""
			(at 0 0 0)
			(layer "B.Fab")
			(effects
				(font
					(size 1.27 1.27)
				)
				(justify mirror)
			)
		)
		(duplicate_pad_numbers_are_jumpers no)
		(fp_line
			(start -4.4323 -0.64008)
			(end -4.4323 4.52628)
			(stroke
				(width 0.1524)
				(type default)
			)
			(layer "B.SilkS")
		)
		(fp_line
			(start -4.4323 4.52628)
			(end -1.5367 4.52628)
			(stroke
				(width 0.1524)
				(type default)
			)
			(layer "B.SilkS")
		)
		(fp_line
			(start -3.302 0.49022)
			(end -3.302 -0.64008)
			(stroke
				(width 0.1524)
				(type default)
			)
			(layer "B.SilkS")
		)
		(fp_line
			(start -2.667 -0.64008)
			(end -2.667 0.49022)
			(stroke
				(width 0.1524)
				(type default)
			)
			(layer "B.SilkS")
		)
		(fp_line
			(start -2.667 0.49022)
			(end -3.302 0.49022)
			(stroke
				(width 0.1524)
				(type default)
			)
			(layer "B.SilkS")
		)
		(fp_line
			(start -1.5367 -0.64008)
			(end -4.4323 -0.64008)
			(stroke
				(width 0.1524)
				(type default)
			)
			(layer "B.SilkS")
		)
		(fp_line
			(start -1.5367 4.52628)
			(end -1.5367 -0.64008)
			(stroke
				(width 0.1524)
				(type default)
			)
			(layer "B.SilkS")
		)
		(fp_circle
			(center 1.324102 -0.479552)
			(end 1.451102 -0.479552)
			(stroke
				(width 0.254)
				(type default)
			)
			(fill no)
			(layer "B.SilkS")
		)
		(fp_poly
			(pts
				(xy -0.7366 4.54152) (xy -0.7366 -0.64008) (xy -4.7244 -0.64008) (xy -5.2324 -0.64008) (xy -5.2324 4.54152)
				(xy -4.7244 4.54152)
			)
			(stroke
				(width 0)
				(type default)
			)
			(fill no)
			(layer "B.CrtYd")
		)
		(fp_line
			(start -5.2324 -0.64008)
			(end -5.2324 4.54152)
			(stroke
				(width 0.1)
				(type default)
			)
			(layer "B.Fab")
		)
		(fp_line
			(start -5.2324 4.54152)
			(end -0.7366 4.54152)
			(stroke
				(width 0.1)
				(type default)
			)
			(layer "B.Fab")
		)
		(fp_line
			(start -3.302 0.49022)
			(end -3.302 -0.64008)
			(stroke
				(width 0.1)
				(type default)
			)
			(layer "B.Fab")
		)
		(fp_line
			(start -2.667 -0.64008)
			(end -2.667 0.49022)
			(stroke
				(width 0.1)
				(type default)
			)
			(layer "B.Fab")
		)
		(fp_line
			(start -2.667 0.49022)
			(end -3.302 0.49022)
			(stroke
				(width 0.1)
				(type default)
			)
			(layer "B.Fab")
		)
		(fp_line
			(start -0.7366 -0.64008)
			(end -5.2324 -0.64008)
			(stroke
				(width 0.1)
				(type default)
			)
			(layer "B.Fab")
		)
		(fp_line
			(start -0.7366 4.54152)
			(end -0.7366 -0.64008)
			(stroke
				(width 0.1)
				(type default)
			)
			(layer "B.Fab")
		)
		(fp_circle
			(center 1.612138 -0.684784)
			(end 1.739138 -0.684784)
			(stroke
				(width 0.254)
				(type default)
			)
			(fill no)
			(layer "B.Fab")
		)
		(pad "1" smd rect
			(at 0 0 180)
			(size 2.159 0.381)
			(layers "B.Cu" "B.Mask" "B.Paste")
			(net "PD_GTL2104_4_DIR")
		)
		(pad "2" smd rect
			(at 0 0.65024 180)
			(size 2.159 0.381)
			(layers "B.Cu" "B.Mask" "B.Paste")
			(net "H_CPU1_PROCHOT_G_R_N")
		)
		(pad "3" smd rect
			(at 0 1.30048 180)
			(size 2.159 0.381)
			(layers "B.Cu" "B.Mask" "B.Paste")
			(net "H_CPU0_PROCHOT_G_R_N")
		)
		(pad "4" smd rect
			(at 0 1.95072 180)
			(size 2.159 0.381)
			(layers "B.Cu" "B.Mask" "B.Paste")
			(net "P0V7_GTL2104_5_VREF")
		)
		(pad "5" smd rect
			(at 0 2.60096 180)
			(size 2.159 0.381)
			(layers "B.Cu" "B.Mask" "B.Paste")
			(net "H_CPU_ERR1_GTL_N")
		)
		(pad "6" smd rect
			(at 0 3.2512 180)
			(size 2.159 0.381)
			(layers "B.Cu" "B.Mask" "B.Paste")
			(net "H_CPU_ERR0_GTL_N")
		)
		(pad "7" smd rect
			(at 0 3.90144 180)
			(size 2.159 0.381)
			(layers "B.Cu" "B.Mask" "B.Paste")
			(net "GND")
		)
		(pad "8" smd rect
			(at -5.969 3.90144 180)
			(size 2.159 0.381)
			(layers "B.Cu" "B.Mask" "B.Paste")
			(net "GND")
		)
		(pad "9" smd rect
			(at -5.969 3.2512 180)
			(size 2.159 0.381)
			(layers "B.Cu" "B.Mask" "B.Paste")
			(net "FM_CPU_ERR0_LVT3_R_N")
		)
		(pad "10" smd rect
			(at -5.969 2.60096 180)
			(size 2.159 0.381)
			(layers "B.Cu" "B.Mask" "B.Paste")
			(net "FM_CPU_ERR1_LVT3_R_N")
		)
		(pad "11" smd rect
			(at -5.969 1.95072 180)
			(size 2.159 0.381)
			(layers "B.Cu" "B.Mask" "B.Paste")
			(net "GND")
		)
		(pad "12" smd rect
			(at -5.969 1.30048 180)
			(size 2.159 0.381)
			(layers "B.Cu" "B.Mask" "B.Paste")
			(net "FM_CPU0_PROCHOT_LVT3_R_N")
		)
		(pad "13" smd rect
			(at -5.969 0.65024 180)
			(size 2.159 0.381)
			(layers "B.Cu" "B.Mask" "B.Paste")
			(net "FM_CPU1_PROCHOT_LVT3_R_N")
		)
		(pad "14" smd rect
			(at -5.969 0 180)
			(size 2.159 0.381)
			(layers "B.Cu" "B.Mask" "B.Paste")
			(net "P3V3")
		)
	)
	(footprint ""
		(layer "B.Cu")
		(at 406.7556 -29.6164)
		(property "Reference" "R25W152"
			(at 0.8382 -0.67818 0)
			(unlocked yes)
			(layer "B.SilkS")
			(effects
				(font
					(size 0.4064 0.254)
					(thickness 0.1524)
				)
				(justify left mirror)
			)
		)
		(property "Value" ""
			(at 0 0 0)
			(layer "B.Fab")
			(effects
				(font
					(size 1.27 1.27)
				)
				(justify mirror)
			)
		)
		(duplicate_pad_numbers_are_jumpers no)
		(fp_poly
			(pts
				(xy 0.2794 -0.1016) (xy -0.2794 -0.1016) (xy -0.2794 0.9906) (xy 0.2794 0.9906)
			)
			(stroke
				(width 0)
				(type default)
			)
			(fill no)
			(layer "B.CrtYd")
		)
		(fp_line
			(start -0.2794 -0.1016)
			(end 0.2794 -0.1016)
			(stroke
				(width 0.1)
				(type default)
			)
			(layer "B.Fab")
		)
		(fp_line
			(start -0.2794 0.9906)
			(end -0.2794 -0.1016)
			(stroke
				(width 0.1)
				(type default)
			)
			(layer "B.Fab")
		)
		(fp_line
			(start 0.2794 -0.1016)
			(end 0.2794 0.9906)
			(stroke
				(width 0.1)
				(type default)
			)
			(layer "B.Fab")
		)
		(fp_line
			(start 0.2794 0.9906)
			(end -0.2794 0.9906)
			(stroke
				(width 0.1)
				(type default)
			)
			(layer "B.Fab")
		)
		(pad "1" smd rect
			(at 0 0 180)
			(size 0.508 0.508)
			(layers "B.Cu" "B.Mask" "B.Paste")
			(net "GND")
		)
		(pad "2" smd rect
			(at 0 0.889 180)
			(size 0.508 0.508)
			(layers "B.Cu" "B.Mask" "B.Paste")
			(net "TP_RGMII2TXD2_GPIOU2")
		)
		(zone
			(layer "B.Cu")
			(hatch none 0.5)
			(connect_pads
				(clearance 0)
			)
			(min_thickness 0.25)
			(keepout
				(tracks allowed)
				(vias not_allowed)
				(pads allowed)
				(copperpour not_allowed)
				(footprints allowed)
			)
			(placement
				(enabled no)
				(sheetname "")
			)
			(fill
				(thermal_gap 0.5)
				(thermal_bridge_width 0.5)
				(island_removal_mode 0)
			)
			(polygon
				(pts
					(xy 407.0096 -29.3624) (xy 406.5016 -29.3624) (xy 406.5016 -28.9814) (xy 407.0096 -28.9814)
				)
			)
		)
		(zone
			(layer "B.Cu")
			(hatch none 0.5)
			(connect_pads
				(clearance 0)
			)
			(min_thickness 0.25)
			(keepout
				(tracks not_allowed)
				(vias allowed)
				(pads allowed)
				(copperpour not_allowed)
				(footprints allowed)
			)
			(placement
				(enabled no)
				(sheetname "")
			)
			(fill
				(thermal_gap 0.5)
				(thermal_bridge_width 0.5)
				(island_removal_mode 0)
			)
			(polygon
				(pts
					(xy 407.0096 -28.9814) (xy 406.5016 -28.9814) (xy 406.5016 -29.3624) (xy 407.0096 -29.3624)
				)
			)
		)
	)
	(footprint ""
		(layer "B.Cu")
		(at 318.797432 1.7018 -90)
		(property "Reference" "C4U4"
			(at 0 0 90)
			(layer "B.SilkS")
			(hide yes)
			(effects
				(font
					(size 1.27 1.27)
				)
				(justify mirror)
			)
		)
		(property "Value" ""
			(at 0 0 90)
			(layer "B.Fab")
			(effects
				(font
					(size 1.27 1.27)
				)
				(justify mirror)
			)
		)
		(duplicate_pad_numbers_are_jumpers no)
		(fp_poly
			(pts
				(xy 0.4953 -0.2032) (xy -0.4953 -0.2032) (xy -0.4953 1.6002) (xy 0.4953 1.6002)
			)
			(stroke
				(width 0)
				(type default)
			)
			(fill no)
			(layer "B.CrtYd")
		)
		(fp_line
			(start -0.4953 1.6002)
			(end 0.4953 1.6002)
			(stroke
				(width 0.1)
				(type default)
			)
			(layer "B.Fab")
		)
		(fp_line
			(start 0.4953 1.6002)
			(end 0.4953 -0.2032)
			(stroke
				(width 0.1)
				(type default)
			)
			(layer "B.Fab")
		)
		(fp_line
			(start -0.4953 -0.2032)
			(end -0.4953 1.6002)
			(stroke
				(width 0.1)
				(type default)
			)
			(layer "B.Fab")
		)
		(fp_line
			(start 0.4953 -0.2032)
			(end -0.4953 -0.2032)
			(stroke
				(width 0.1)
				(type default)
			)
			(layer "B.Fab")
		)
		(pad "1" smd rect
			(at 0 0 90)
			(size 0.762 0.889)
			(layers "B.Cu" "B.Mask" "B.Paste")
			(net "PVPP_ABC")
		)
		(pad "2" smd rect
			(at 0 1.397 90)
			(size 0.762 0.889)
			(layers "B.Cu" "B.Mask" "B.Paste")
			(net "GND")
		)
		(zone
			(layer "B.Cu")
			(hatch none 0.5)
			(connect_pads
				(clearance 0)
			)
			(min_thickness 0.25)
			(keepout
				(tracks not_allowed)
				(vias allowed)
				(pads allowed)
				(copperpour not_allowed)
				(footprints allowed)
			)
			(placement
				(enabled no)
				(sheetname "")
			)
			(fill
				(thermal_gap 0.5)
				(thermal_bridge_width 0.5)
				(island_removal_mode 0)
			)
			(polygon
				(pts
					(xy 318.352932 2.0828) (xy 318.352932 1.3208) (xy 317.844932 1.3208) (xy 317.844932 2.0828)
				)
			)
		)
	)
	(footprint ""
		(layer "B.Cu")
		(at 168.656 -87.757)
		(property "Reference" "R6P5"
			(at 0 0 0)
			(layer "B.SilkS")
			(hide yes)
			(effects
				(font
					(size 1.27 1.27)
				)
				(justify mirror)
			)
		)
		(property "Value" ""
			(at 0 0 0)
			(layer "B.Fab")
			(effects
				(font
					(size 1.27 1.27)
				)
				(justify mirror)
			)
		)
		(duplicate_pad_numbers_are_jumpers no)
		(fp_poly
			(pts
				(xy 0.2794 -0.1016) (xy -0.2794 -0.1016) (xy -0.2794 0.9906) (xy 0.2794 0.9906)
			)
			(stroke
				(width 0)
				(type default)
			)
			(fill no)
			(layer "B.CrtYd")
		)
		(fp_line
			(start -0.2794 -0.1016)
			(end 0.2794 -0.1016)
			(stroke
				(width 0.1)
				(type default)
			)
			(layer "B.Fab")
		)
		(fp_line
			(start -0.2794 0.9906)
			(end -0.2794 -0.1016)
			(stroke
				(width 0.1)
				(type default)
			)
			(layer "B.Fab")
		)
		(fp_line
			(start 0.2794 -0.1016)
			(end 0.2794 0.9906)
			(stroke
				(width 0.1)
				(type default)
			)
			(layer "B.Fab")
		)
		(fp_line
			(start 0.2794 0.9906)
			(end -0.2794 0.9906)
			(stroke
				(width 0.1)
				(type default)
			)
			(layer "B.Fab")
		)
		(pad "1" smd rect
			(at 0 0 180)
			(size 0.508 0.508)
			(layers "B.Cu" "B.Mask" "B.Paste")
			(net "CLK_100M_CPU1_BCLK0_DP")
		)
		(pad "2" smd rect
			(at 0 0.889 180)
			(size 0.508 0.508)
			(layers "B.Cu" "B.Mask" "B.Paste")
			(net "GND")
		)
		(zone
			(layer "B.Cu")
			(hatch none 0.5)
			(connect_pads
				(clearance 0)
			)
			(min_thickness 0.25)
			(keepout
				(tracks allowed)
				(vias not_allowed)
				(pads allowed)
				(copperpour not_allowed)
				(footprints allowed)
			)
			(placement
				(enabled no)
				(sheetname "")
			)
			(fill
				(thermal_gap 0.5)
				(thermal_bridge_width 0.5)
				(island_removal_mode 0)
			)
			(polygon
				(pts
					(xy 168.91 -87.503) (xy 168.402 -87.503) (xy 168.402 -87.122) (xy 168.91 -87.122)
				)
			)
		)
		(zone
			(layer "B.Cu")
			(hatch none 0.5)
			(connect_pads
				(clearance 0)
			)
			(min_thickness 0.25)
			(keepout
				(tracks not_allowed)
				(vias allowed)
				(pads allowed)
				(copperpour not_allowed)
				(footprints allowed)
			)
			(placement
				(enabled no)
				(sheetname "")
			)
			(fill
				(thermal_gap 0.5)
				(thermal_bridge_width 0.5)
				(island_removal_mode 0)
			)
			(polygon
				(pts
					(xy 168.91 -87.122) (xy 168.402 -87.122) (xy 168.402 -87.503) (xy 168.91 -87.503)
				)
			)
		)
	)
	(footprint ""
		(layer "B.Cu")
		(at 178.562 -54.991 -90)
		(property "Reference" "C6R8"
			(at 0 0 90)
			(layer "B.SilkS")
			(hide yes)
			(effects
				(font
					(size 1.27 1.27)
				)
				(justify mirror)
			)
		)
		(property "Value" ""
			(at 0 0 90)
			(layer "B.Fab")
			(effects
				(font
					(size 1.27 1.27)
				)
				(justify mirror)
			)
		)
		(duplicate_pad_numbers_are_jumpers no)
		(fp_poly
			(pts
				(xy 0.7239 -0.2159) (xy -0.7239 -0.2159) (xy -0.7239 1.9939) (xy 0.7239 1.9939)
			)
			(stroke
				(width 0)
				(type default)
			)
			(fill no)
			(layer "B.CrtYd")
		)
		(fp_line
			(start -0.7239 1.9939)
			(end -0.7239 -0.2159)
			(stroke
				(width 0.1)
				(type default)
			)
			(layer "B.Fab")
		)
		(fp_line
			(start 0.7239 1.9939)
			(end -0.7239 1.9939)
			(stroke
				(width 0.1)
				(type default)
			)
			(layer "B.Fab")
		)
		(fp_line
			(start -0.7239 -0.2159)
			(end 0.7239 -0.2159)
			(stroke
				(width 0.1)
				(type default)
			)
			(layer "B.Fab")
		)
		(fp_line
			(start 0.7239 -0.2159)
			(end 0.7239 1.9939)
			(stroke
				(width 0.1)
				(type default)
			)
			(layer "B.Fab")
		)
		(pad "1" smd rect
			(at 0 0 90)
			(size 1.27 1.016)
			(layers "B.Cu" "B.Mask" "B.Paste")
			(net "VR_FET_SW_P12V_STBY_PVCCIN_CPU0")
		)
		(pad "2" smd rect
			(at 0 1.778 90)
			(size 1.27 1.016)
			(layers "B.Cu" "B.Mask" "B.Paste")
			(net "GND")
		)
		(zone
			(layer "B.Cu")
			(hatch none 0.5)
			(connect_pads
				(clearance 0)
			)
			(min_thickness 0.25)
			(keepout
				(tracks not_allowed)
				(vias allowed)
				(pads allowed)
				(copperpour not_allowed)
				(footprints allowed)
			)
			(placement
				(enabled no)
				(sheetname "")
			)
			(fill
				(thermal_gap 0.5)
				(thermal_bridge_width 0.5)
				(island_removal_mode 0)
			)
			(polygon
				(pts
					(xy 178.054 -54.356) (xy 178.054 -55.626) (xy 177.292 -55.626) (xy 177.292 -54.356)
				)
			)
		)
	)
	(footprint ""
		(layer "B.Cu")
		(at 80.757268 -17.7546 -90)
		(property "Reference" "C8T10"
			(at -1.848866 0.752348 270)
			(unlocked yes)
			(layer "B.SilkS")
			(effects
				(font
					(size 1.27 0.9652)
					(thickness 0.1524)
				)
				(justify mirror)
			)
		)
		(property "Value" ""
			(at 0 0 90)
			(layer "B.Fab")
			(effects
				(font
					(size 1.27 1.27)
				)
				(justify mirror)
			)
		)
		(duplicate_pad_numbers_are_jumpers no)
		(fp_rect
			(start 0.500126 1.598422)
			(end -0.500126 -0.201422)
			(stroke
				(width 0)
				(type default)
			)
			(fill no)
			(layer "B.CrtYd")
		)
		(fp_line
			(start -0.500126 1.598422)
			(end 0.500126 1.598422)
			(stroke
				(width 0.1)
				(type default)
			)
			(layer "B.Fab")
		)
		(fp_line
			(start 0.500126 1.598422)
			(end 0.500126 -0.201422)
			(stroke
				(width 0.1)
				(type default)
			)
			(layer "B.Fab")
		)
		(fp_line
			(start -0.500126 -0.201422)
			(end -0.500126 1.598422)
			(stroke
				(width 0.1)
				(type default)
			)
			(layer "B.Fab")
		)
		(fp_line
			(start 0.500126 -0.201422)
			(end -0.500126 -0.201422)
			(stroke
				(width 0.1)
				(type default)
			)
			(layer "B.Fab")
		)
		(pad "1" smd rect
			(at 0 0 180)
			(size 0.889 0.9906)
			(layers "B.Cu" "B.Mask" "B.Paste")
			(net "PVDDQ_GHJ")
		)
		(pad "2" smd rect
			(at 0 1.397 180)
			(size 0.889 0.9906)
			(layers "B.Cu" "B.Mask" "B.Paste")
			(net "GND")
		)
		(zone
			(layer "B.Cu")
			(hatch none 0.5)
			(connect_pads
				(clearance 0)
			)
			(min_thickness 0.25)
			(keepout
				(tracks not_allowed)
				(vias allowed)
				(pads allowed)
				(copperpour not_allowed)
				(footprints allowed)
			)
			(placement
				(enabled no)
				(sheetname "")
			)
			(fill
				(thermal_gap 0.5)
				(thermal_bridge_width 0.5)
				(island_removal_mode 0)
			)
			(polygon
				(pts
					(xy 79.804768 -17.2593) (xy 80.312768 -17.2593) (xy 80.312768 -18.2499) (xy 79.804768 -18.2499)
				)
			)
		)
		(zone
			(layer "B.Cu")
			(hatch none 0.5)
			(connect_pads
				(clearance 0)
			)
			(min_thickness 0.25)
			(keepout
				(tracks allowed)
				(vias not_allowed)
				(pads allowed)
				(copperpour not_allowed)
				(footprints allowed)
			)
			(placement
				(enabled no)
				(sheetname "")
			)
			(fill
				(thermal_gap 0.5)
				(thermal_bridge_width 0.5)
				(island_removal_mode 0)
			)
			(polygon
				(pts
					(xy 79.804768 -17.2593) (xy 80.312768 -17.2593) (xy 80.312768 -18.2499) (xy 79.804768 -18.2499)
				)
			)
		)
	)
)
